# BARRELEYE_G2-MB-PVT-X04-HW-BOM-X26_20180122_Final.xls.xlsx — TLA (bom)
| FOXCONN TECHNOLOGY GROUP |  |  |  |  |  |  |  |  |  |
| BILL OF MATERIAL |  |  |  |  |  |  |  |  |  |
| AA P/N | 1A42DLQ00-600-G | CUSTOMER | RACKSPACE | Customer P/N | N/A | Product Code |  |  |  |
| PWA P/N |  | PWA DESCRIPTION | ASSY,MB,R_ZAIUS |  |  | PWA REV | PVT-X04 | Prepared By SE |  |
| Item | FOXCONN P/N | Customer P/N | Part Description | Manufacturer  Full Name | Manufacturer  Part Number | Qty | RoHS Status | Location | Remark |
| 1 | 1A424CJ00-600-G |  | LOAD FRAME ASM,ZNEW,IBM,01AF120,G,00 | FOXCONN / EPD5 | 1A424CJ00-600-G | 2 | G |  | Rev:A IBM PN:01AF120 |
| 2 | 1A424CG00-600-G |  | LOAD FRAME ASM,ZNEW,IBM,01AF118,G,00 | FOXCONN / EPD5 | 1A424CG00-600-G | 2 | G |  | Rev:A IBM PN:01AF118 |
| 3 | 2A584VU00-192-G |  | BACKPLATE SCREW | Supply Technologies | 46K4434 | 8 | G |  | Rev:A |
| 4 | 1A42FV700-13E-G |  | Power 9 CPU Backplate (Combined with Mylar and Dowel) | Aavid | 360493 | 2 | G |  | Rev:A (Reference IBM PN:01AF136) |
|  | 1A42FL600-H8U-G |  | Power 9 CPU Backplate (Combined with Mylar and Dowel) ; 2nd | Furukawa | HS855380 |  | G |  | Rev 01 and Rev B are the same can be common parts. Rev:01 |
| 5 | 7J-004-938 |  | L6 LABEL ( 12.7*11.1mm) | FOXCONN / EPD1 | 7J-004-938 | 1 | G |  | ID label. |
| 6 | 1A42EG100-653-G |  | Switch CAP blue. | DIPTRONICS | KTSC-62B | 1 | G |  | Rev:H Color Blue for Power button. |
| 7 | 1A42EGF00-653-G |  | Switch CAP black. | DIPTRONICS | KTSC-62K | 1 | G |  | Rev:H Color Black for Reset button. |
| 8 | 480124F00-13E-G |  | Heat sink (40x80x10 mm) | Aavid | 658031 | 2 | G |  | Rev:A For VTM-1 |
|  | 480124E00-H8U-G |  | Heat sink (40x80x10 mm) | Furukawa | HS855362 |  | G |  | Rev:01 For VTM-1 |
| 9 | 480124G00-13E-G |  | Heat sink(80x57.3x15 mm) | Aavid | 658032 | 2 | G |  | Rev:A For VTM-2 |
|  | 480124D00-H8U-G |  | Heat sink(80x57.3x15 mm) | Furukawa | HS855372 |  | G |  | Rev:01 For VTM-2 |
| 10 | 2A3000M00-600-G |  | SPACER H:6.6MM, THICKNESS:3.2MM | KANG YANG | ULCO6.6-3.1(GR) | 1 | G |  | Rev:A1 FOR M.2 CARD |
| 11 | 2A3000K00-600-G |  | SPACER H:12MM, THICKNESS:3.2MM | KANG YANG | MSPN-12 | 4 | G |  | Rev:A FOR OCP CARD |
| 12 | 2A3000L00-600-G |  | SPACER H:9MM, THICKNESS:3.2MM | KANG YANG | MSPN-9 | 2 | G |  | Rev:A FOR LV CARD |
| 13 | 7D115LM00-600-G |  | Rubber=12x4.6x7mm | PINGOOD | L120704MP-X3O | 2 | G |  | Rev:X01 For Heat sink VTM-2 |
| 14 | 7J-004-1027 |  | LBL,ADRS,MAC (16 x 16 mm) | FOXCONN / EPD1 | 7J-004-1027 | 1 | G |  | For LOM, BMC, NCSI |
| 15 | 7J-004-1618 |  | LBL,CPU Socket | Sunway | 7J-004-1618 | 2 | G |  | For CPU Socket |
| 16 | 8CH01-120 |  | 8_rubber-support-vtm_barreleye | Foxconn-EPD5 | 8CH01-120 | 2 | G |  | Rev:X1 For Barreleye G2 MB Rubber's Contact window: <name> |
| 17 | 7J-004-1100 |  | MAC Label (37.5 * 9mm) | Foxconn/EPD1 | 7J-004-1100 | 3 | G |  | For BMC & HOST MAC.(To attach the label on the MB board) |
